# T6G (Grand Teton) — schematic netlist excerpt (pin names and nets, part order shuffled) for the footprints in the layout excerpt that follows; sources: Cadence DE-HDL packaged netlist, KiCad conversion of 04192023_DAF0TMB3IC0_F0TG_MB_C_brd_V02_OCP.brd

X10  TP_TDR_4P_FTS  TP_TDR_4P_DIP EMPTY  pkg TH  page 260
  S1  = TDR_DIFF_80_IN3_DN
  P1  = T1_GND
  P2  = T1_GND
  S2  = TDR_DIFF_80_IN3_DP

C1096  Q_CAP  0.1UF 25V 10% X7R  pkg 0402  page 357 : A = P3V3_AUX ; B = GND

(kicad_pcb
	(version 20260206)
	(generator "pcbnew")
	(generator_version "10.0")
	(general
		(thickness 1.6)
		(legacy_teardrops no)
	)
	(paper "A4")
	(title_block
		(title "04192023_DAF0TMB3IC0_F0TG_MB_C_brd_V02_OCP.brd")
		(comment 1 "Grand Teton / footprints 24-25 of 8354")
	)
	(layers
		(0 "F.Cu" signal "TOP")
		(4 "In1.Cu" signal "GND")
		(6 "In2.Cu" signal "IN1")
		(8 "In3.Cu" signal "GND1")
		(10 "In4.Cu" signal "IN2")
		(12 "In5.Cu" signal "GND2")
		(14 "In6.Cu" signal "IN3")
		(16 "In7.Cu" signal "GND3")
		(18 "In8.Cu" signal "VCC")
		(20 "In9.Cu" signal "VCC1")
		(22 "In10.Cu" signal "GND4")
		(24 "In11.Cu" signal "IN4")
		(26 "In12.Cu" signal "GND5")
		(28 "In13.Cu" signal "IN5")
		(30 "In14.Cu" signal "GND6")
		(32 "In15.Cu" signal "IN6")
		(34 "In16.Cu" signal "GND7")
		(2 "B.Cu" signal "BOTTOM")
		(9 "F.Adhes" user "F.Adhesive")
		(11 "B.Adhes" user "B.Adhesive")
		(13 "F.Paste" user "Package Geometry/Pastemask Top")
		(15 "B.Paste" user "Package Geometry/Pastemask Bottom")
		(5 "F.SilkS" user "Ref Des/Silkscreen Top")
		(7 "B.SilkS" user "Ref Des/Silkscreen Bottom")
		(1 "F.Mask" user "Board Geometry/Soldermask Top")
		(3 "B.Mask" user "Board Geometry/Soldermask Bottom")
		(17 "Dwgs.User" user "User.Drawings")
		(19 "Cmts.User" user "User.Comments")
		(21 "Eco1.User" user "User.Eco1")
		(23 "Eco2.User" user "User.Eco2")
		(25 "Edge.Cuts" user "Board Geometry/Outline")
		(27 "Margin" user)
		(31 "F.CrtYd" user "Package Geometry/Place Bound Top")
		(29 "B.CrtYd" user "Package Geometry/Place Bound Bottom")
		(35 "F.Fab" user "Ref Des/Assembly Top")
		(33 "B.Fab" user "Ref Des/Assembly Bottom")
	)
	(footprint ""
		(layer "F.Cu")
		(at 493.36833 -298.352718 90)
		(property "Reference" "X10"
			(at -1.985264 1.132586 0)
			(unlocked yes)
			(layer "F.SilkS")
			(effects
				(font
					(size 0.7874 0.5842)
					(thickness 0.1524)
				)
				(justify left)
			)
		)
		(property "Value" ""
			(at 0 0 90)
			(layer "F.Fab")
			(effects
				(font
					(size 1.27 1.27)
				)
			)
		)
		(property "User Part Number" "N_A"
			(at 1.30175 1.27 180)
			(unlocked yes)
			(layer "Cmts.User")
			(hide yes)
			(effects
				(font
					(size 0.635 0.4064)
					(thickness 0.1524)
				)
			)
		)
		(property "Device Type" "TP_TDR_4P_FTS_TH-TP_TDR_4P_DIP,EMPTY,TP15"
			(at 1.30175 1.27 180)
			(unlocked yes)
			(layer "F.Fab")
			(hide yes)
			(effects
				(font
					(size 0.635 0.4064)
					(thickness 0.1524)
				)
			)
		)
		(duplicate_pad_numbers_are_jumpers no)
		(fp_line
			(start 2.54 -1.27)
			(end 0 -1.27)
			(stroke
				(width 0.1524)
				(type default)
			)
			(layer "F.SilkS")
		)
		(fp_line
			(start 0 -1.27)
			(end 0 -0.635)
			(stroke
				(width 0.1524)
				(type default)
			)
			(layer "F.SilkS")
		)
		(fp_line
			(start 2.54 -1.1303)
			(end 2.54 -1.27)
			(stroke
				(width 0.1524)
				(type default)
			)
			(layer "F.SilkS")
		)
		(fp_line
			(start 0 0.635)
			(end 0 1.905)
			(stroke
				(width 0.1524)
				(type default)
			)
			(layer "F.SilkS")
		)
		(fp_line
			(start 2.54 1.4097)
			(end 2.54 1.1303)
			(stroke
				(width 0.1524)
				(type default)
			)
			(layer "F.SilkS")
		)
		(fp_line
			(start 0 3.175)
			(end 0 3.81)
			(stroke
				(width 0.1524)
				(type default)
			)
			(layer "F.SilkS")
		)
		(fp_line
			(start 2.54 3.81)
			(end 2.54 3.6703)
			(stroke
				(width 0.1524)
				(type default)
			)
			(layer "F.SilkS")
		)
		(fp_line
			(start 0 3.81)
			(end 2.54 3.81)
			(stroke
				(width 0.1524)
				(type default)
			)
			(layer "F.SilkS")
		)
		(fp_poly
			(pts
				(xy -0.761746 0) (xy -2.285746 0.762) (xy -2.285746 -0.762)
			)
			(stroke
				(width 0)
				(type default)
			)
			(fill yes)
			(layer "F.SilkS")
		)
		(fp_line
			(start 2.54 -1.27)
			(end 0 -1.27)
			(stroke
				(width 0.1)
				(type default)
			)
			(layer "F.Fab")
		)
		(fp_line
			(start 0 -1.27)
			(end 0 3.81)
			(stroke
				(width 0.1)
				(type default)
			)
			(layer "F.Fab")
		)
		(fp_line
			(start 2.54 3.81)
			(end 2.54 -1.27)
			(stroke
				(width 0.1)
				(type default)
			)
			(layer "F.Fab")
		)
		(fp_line
			(start 0 3.81)
			(end 2.54 3.81)
			(stroke
				(width 0.1)
				(type default)
			)
			(layer "F.Fab")
		)
		(fp_poly
			(pts
				(xy -0.761746 0) (xy -2.285746 -0.762) (xy -2.285746 0.762)
			)
			(stroke
				(width 0)
				(type default)
			)
			(fill yes)
			(layer "F.Fab")
		)
		(pad "1" thru_hole circle
			(at 0 0 90)
			(size 1.0033 1.0033)
			(drill 0.249936)
			(layers "*.Cu" "*.Mask")
			(remove_unused_layers no)
			(net "TDR_DIFF_80_IN3_DN")
			(clearance 0.10795)
			(thermal_gap 0.10795)
			(padstack
				(mode front_inner_back)
				(layer "Inner"
					(shape circle)
					(size 0.8001 0.8001)
					(clearance 0.1524)
				)
				(layer "B.Cu"
					(shape circle)
					(size 1.0033 1.0033)
					(clearance 0.10795)
				)
			)
		)
		(pad "2" thru_hole circle
			(at 2.54 0 90)
			(size 1.9939 1.9939)
			(drill 0.249936)
			(layers "*.Cu" "*.Mask")
			(remove_unused_layers no)
			(net "T1_GND")
			(clearance 0.10795)
			(thermal_gap 0.10795)
			(padstack
				(mode front_inner_back)
				(layer "Inner"
					(shape circle)
					(size 0.8001 0.8001)
					(clearance 0.1524)
				)
				(layer "B.Cu"
					(shape circle)
					(size 1.9939 1.9939)
					(clearance 0.10795)
				)
			)
		)
		(pad "3" thru_hole circle
			(at 2.54 2.54 90)
			(size 1.9939 1.9939)
			(drill 0.249936)
			(layers "*.Cu" "*.Mask")
			(remove_unused_layers no)
			(net "T1_GND")
			(clearance 0.10795)
			(thermal_gap 0.10795)
			(padstack
				(mode front_inner_back)
				(layer "Inner"
					(shape circle)
					(size 0.8001 0.8001)
					(clearance 0.1524)
				)
				(layer "B.Cu"
					(shape circle)
					(size 1.9939 1.9939)
					(clearance 0.10795)
				)
			)
		)
		(pad "4" thru_hole circle
			(at 0 2.54 90)
			(size 1.0033 1.0033)
			(drill 0.249936)
			(layers "*.Cu" "*.Mask")
			(remove_unused_layers no)
			(net "TDR_DIFF_80_IN3_DP")
			(clearance 0.10795)
			(thermal_gap 0.10795)
			(padstack
				(mode front_inner_back)
				(layer "Inner"
					(shape circle)
					(size 0.8001 0.8001)
					(clearance 0.1524)
				)
				(layer "B.Cu"
					(shape circle)
					(size 1.0033 1.0033)
					(clearance 0.10795)
				)
			)
		)
	)
	(footprint ""
		(layer "F.Cu")
		(at 328.092308 -102.52075)
		(property "Reference" "C1096"
			(at 0 0 0)
			(layer "F.SilkS")
			(hide yes)
			(effects
				(font
					(size 1.27 1.27)
				)
			)
		)
		(property "Value" ""
			(at 0 0 0)
			(layer "F.Fab")
			(effects
				(font
					(size 1.27 1.27)
				)
			)
		)
		(duplicate_pad_numbers_are_jumpers no)
		(fp_line
			(start -0.7874 -0.4064)
			(end 0.7874 -0.4064)
			(stroke
				(width 0.1524)
				(type default)
			)
			(layer "F.SilkS")
		)
		(fp_line
			(start -0.7874 0.4064)
			(end -0.7874 -0.4064)
			(stroke
				(width 0.1524)
				(type default)
			)
			(layer "F.SilkS")
		)
		(fp_line
			(start 0.7874 -0.4064)
			(end 0.7874 0.4064)
			(stroke
				(width 0.1524)
				(type default)
			)
			(layer "F.SilkS")
		)
		(fp_line
			(start 0.7874 0.4064)
			(end -0.7874 0.4064)
			(stroke
				(width 0.1524)
				(type default)
			)
			(layer "F.SilkS")
		)
		(fp_line
			(start -0.67945 -0.305054)
			(end -0.12065 -0.305054)
			(stroke
				(width 0.1)
				(type default)
			)
			(layer "F.Fab")
		)
		(fp_line
			(start -0.67945 0.3048)
			(end -0.67945 -0.305054)
			(stroke
				(width 0.1)
				(type default)
			)
			(layer "F.Fab")
		)
		(fp_line
			(start -0.12065 -0.305054)
			(end -0.12065 -0.2794)
			(stroke
				(width 0.1)
				(type default)
			)
			(layer "F.Fab")
		)
		(fp_line
			(start -0.12065 -0.2794)
			(end 0.12065 -0.2794)
			(stroke
				(width 0.1)
				(type default)
			)
			(layer "F.Fab")
		)
		(fp_line
			(start -0.12065 0.2794)
			(end -0.12065 0.3048)
			(stroke
				(width 0.1)
				(type default)
			)
			(layer "F.Fab")
		)
		(fp_line
			(start -0.12065 0.3048)
			(end -0.67945 0.3048)
			(stroke
				(width 0.1)
				(type default)
			)
			(layer "F.Fab")
		)
		(fp_line
			(start 0.120396 0.2794)
			(end -0.12065 0.2794)
			(stroke
				(width 0.1)
				(type default)
			)
			(layer "F.Fab")
		)
		(fp_line
			(start 0.120396 0.3048)
			(end 0.120396 0.2794)
			(stroke
				(width 0.1)
				(type default)
			)
			(layer "F.Fab")
		)
		(fp_line
			(start 0.12065 -0.3048)
			(end 0.67945 -0.3048)
			(stroke
				(width 0.1)
				(type default)
			)
			(layer "F.Fab")
		)
		(fp_line
			(start 0.12065 -0.2794)
			(end 0.12065 -0.3048)
			(stroke
				(width 0.1)
				(type default)
			)
			(layer "F.Fab")
		)
		(fp_line
			(start 0.67945 -0.3048)
			(end 0.67945 0.3048)
			(stroke
				(width 0.1)
				(type default)
			)
			(layer "F.Fab")
		)
		(fp_line
			(start 0.67945 0.3048)
			(end 0.120396 0.3048)
			(stroke
				(width 0.1)
				(type default)
			)
			(layer "F.Fab")
		)
		(pad "1" smd circle
			(at -0.40005 0)
			(size 0 0)
			(layers "F.Cu" "F.Mask" "F.Paste")
			(net "P3V3_AUX")
		)
		(pad "2" smd circle
			(at 0.40005 0)
			(size 0 0)
			(layers "F.Cu" "F.Mask" "F.Paste")
			(net "GND")
		)
	)
)
